# BASEBOARD_FAB2 (Tioga Pass) — schematic netlist excerpt (pin names and nets, part order shuffled) for the footprints in the layout excerpt that follows; sources: Cadence DE-HDL packaged netlist, KiCad conversion of Wiwynn_Tioga_Pass_MB.brd

R7B1  RES  33.2 1% CHIP  pkg 0402  page 218 : A = IRQ_PVDDQ_DEF_VRHOT_LVT3_R_N ; B = IRQ_PVDDQ_DEF_VRHOT_LVT3_N
RT13  1R3F-GP  1%  pkg RCL_GP  page 208 : \1\ = VR_PVCCIN_CPU1_PHASE4_RC ; \2\ = GND
C2G14  CAP_A  47UF 4V 20% X5R  pkg 0603V  page 225 : A = PVDDQ_GHJ ; B = GND

(kicad_pcb
	(version 20260206)
	(generator "pcbnew")
	(generator_version "10.0")
	(general
		(thickness 1.6)
		(legacy_teardrops no)
	)
	(paper "A4")
	(title_block
		(title "Wiwynn_Tioga_Pass_MB.brd")
		(comment 1 "Tioga Pass / footprints 253-255 of 4770")
	)
	(layers
		(0 "F.Cu" signal "TOP")
		(4 "In1.Cu" signal "L2GND")
		(6 "In2.Cu" signal "L3")
		(8 "In3.Cu" signal "L4GND")
		(10 "In4.Cu" signal "L5")
		(12 "In5.Cu" signal "L6GND")
		(14 "In6.Cu" signal "L7VCC")
		(16 "In7.Cu" signal "L8VCC")
		(18 "In8.Cu" signal "L9GND")
		(20 "In9.Cu" signal "L10")
		(22 "In10.Cu" signal "L11GND")
		(24 "In11.Cu" signal "L12")
		(26 "In12.Cu" signal "L13GND")
		(2 "B.Cu" signal "BOTTOM")
		(9 "F.Adhes" user "F.Adhesive")
		(11 "B.Adhes" user "B.Adhesive")
		(13 "F.Paste" user "Package Geometry/Pastemask Top")
		(15 "B.Paste" user "Package Geometry/Pastemask Bottom")
		(5 "F.SilkS" user "Ref Des/Silkscreen Top")
		(7 "B.SilkS" user "Ref Des/Silkscreen Bottom")
		(1 "F.Mask" user "Board Geometry/Soldermask Top")
		(3 "B.Mask" user "Board Geometry/Soldermask Bottom")
		(17 "Dwgs.User" user "User.Drawings")
		(19 "Cmts.User" user "User.Comments")
		(21 "Eco1.User" user "User.Eco1")
		(23 "Eco2.User" user "User.Eco2")
		(25 "Edge.Cuts" user "Board Geometry/Outline")
		(27 "Margin" user)
		(31 "F.CrtYd" user "Package Geometry/Place Bound Top")
		(29 "B.CrtYd" user "Package Geometry/Place Bound Bottom")
		(35 "F.Fab" user "Ref Des/Assembly Top")
		(33 "B.Fab" user "Ref Des/Assembly Bottom")
	)
	(footprint ""
		(layer "F.Cu")
		(at 35.9664 -77.7494 -90)
		(property "Reference" "RT13"
			(at 0 0 270)
			(layer "F.SilkS")
			(hide yes)
			(effects
				(font
					(size 1.27 1.27)
				)
			)
		)
		(property "Value" "*"
			(at -0.0254 -2.6289 270)
			(unlocked yes)
			(layer "F.Fab")
			(hide yes)
			(effects
				(font
					(size 1.27 1.016)
					(thickness 0.1524)
				)
			)
		)
		(property "Device Type" "1R3F-GP_RCL_GP-1R3F-GP,64.1R00A"
			(at -0.0254 -4.1529 270)
			(unlocked yes)
			(layer "F.Fab")
			(hide yes)
			(effects
				(font
					(size 1.27 1.016)
					(thickness 0.1524)
				)
			)
		)
		(duplicate_pad_numbers_are_jumpers no)
		(fp_line
			(start -0.4826 0)
			(end -0.2032 0)
			(stroke
				(width 0.2032)
				(type default)
			)
			(layer "F.SilkS")
		)
		(fp_line
			(start 0.2032 0)
			(end 0.4826 0)
			(stroke
				(width 0.2032)
				(type default)
			)
			(layer "F.SilkS")
		)
		(fp_rect
			(start -0.5842 1.3335)
			(end 0.5842 -1.3335)
			(stroke
				(width 0)
				(type default)
			)
			(fill no)
			(layer "F.CrtYd")
		)
		(fp_rect
			(start -0.5842 1.3335)
			(end 0.5842 -1.3335)
			(stroke
				(width 0)
				(type default)
			)
			(fill no)
			(layer "F.Fab")
		)
		(pad "1" smd custom
			(at 0 -0.762 270)
			(size 0.2159 0.2159)
			(layers "F.Cu" "F.Mask" "F.Paste")
			(net "VR_PVCCIN_CPU1_PHASE4_RC")
			(options
				(clearance outline)
				(anchor circle)
			)
			(primitives
				(gr_poly
					(pts
						(arc
							(start -0.3302 -0.4318)
							(mid -0.402042 -0.402042)
							(end -0.4318 -0.3302)
						)
						(arc
							(start -0.4318 0.3302)
							(mid -0.402042 0.402042)
							(end -0.3302 0.4318)
						)
						(arc
							(start 0.3302 0.4318)
							(mid 0.402042 0.402042)
							(end 0.4318 0.3302)
						)
						(arc
							(start 0.4318 -0.3302)
							(mid 0.402042 -0.402042)
							(end 0.3302 -0.4318)
						)
					)
					(width 0)
					(fill yes)
				)
			)
		)
		(pad "2" smd custom
			(at 0 0.762 270)
			(size 0.2159 0.2159)
			(layers "F.Cu" "F.Mask" "F.Paste")
			(net "GND")
			(options
				(clearance outline)
				(anchor circle)
			)
			(primitives
				(gr_poly
					(pts
						(arc
							(start -0.3302 -0.4318)
							(mid -0.402042 -0.402042)
							(end -0.4318 -0.3302)
						)
						(arc
							(start -0.4318 0.3302)
							(mid -0.402042 0.402042)
							(end -0.3302 0.4318)
						)
						(arc
							(start 0.3302 0.4318)
							(mid 0.402042 0.402042)
							(end 0.4318 0.3302)
						)
						(arc
							(start 0.4318 -0.3302)
							(mid 0.402042 -0.402042)
							(end 0.3302 -0.4318)
						)
					)
					(width 0)
					(fill yes)
				)
			)
		)
	)
	(footprint ""
		(layer "F.Cu")
		(at 104.5591 -3.3528 90)
		(property "Reference" "C2G14"
			(at 1.848866 0.752348 90)
			(unlocked yes)
			(layer "F.SilkS")
			(effects
				(font
					(size 1.27 0.9652)
					(thickness 0.1524)
				)
			)
		)
		(property "Value" ""
			(at 0 0 90)
			(layer "F.Fab")
			(effects
				(font
					(size 1.27 1.27)
				)
			)
		)
		(duplicate_pad_numbers_are_jumpers no)
		(fp_rect
			(start -0.500126 1.598422)
			(end 0.500126 -0.201422)
			(stroke
				(width 0)
				(type default)
			)
			(fill no)
			(layer "F.CrtYd")
		)
		(fp_line
			(start 0.500126 -0.201422)
			(end 0.500126 1.598422)
			(stroke
				(width 0.1)
				(type default)
			)
			(layer "F.Fab")
		)
		(fp_line
			(start -0.500126 -0.201422)
			(end 0.500126 -0.201422)
			(stroke
				(width 0.1)
				(type default)
			)
			(layer "F.Fab")
		)
		(fp_line
			(start 0.500126 1.598422)
			(end -0.500126 1.598422)
			(stroke
				(width 0.1)
				(type default)
			)
			(layer "F.Fab")
		)
		(fp_line
			(start -0.500126 1.598422)
			(end -0.500126 -0.201422)
			(stroke
				(width 0.1)
				(type default)
			)
			(layer "F.Fab")
		)
		(pad "1" smd rect
			(at 0 0)
			(size 0.889 0.9906)
			(layers "F.Cu" "F.Mask" "F.Paste")
			(net "PVDDQ_GHJ")
		)
		(pad "2" smd rect
			(at 0 1.397)
			(size 0.889 0.9906)
			(layers "F.Cu" "F.Mask" "F.Paste")
			(net "GND")
		)
		(zone
			(layer "F.Cu")
			(hatch none 0.5)
			(connect_pads
				(clearance 0)
			)
			(min_thickness 0.25)
			(keepout
				(tracks allowed)
				(vias not_allowed)
				(pads allowed)
				(copperpour not_allowed)
				(footprints allowed)
			)
			(placement
				(enabled no)
				(sheetname "")
			)
			(fill
				(thermal_gap 0.5)
				(thermal_bridge_width 0.5)
				(island_removal_mode 0)
			)
			(polygon
				(pts
					(xy 105.5116 -2.8575) (xy 105.5116 -3.8481) (xy 105.0036 -3.8481) (xy 105.0036 -2.8575)
				)
			)
		)
		(zone
			(layer "F.Cu")
			(hatch none 0.5)
			(connect_pads
				(clearance 0)
			)
			(min_thickness 0.25)
			(keepout
				(tracks not_allowed)
				(vias allowed)
				(pads allowed)
				(copperpour not_allowed)
				(footprints allowed)
			)
			(placement
				(enabled no)
				(sheetname "")
			)
			(fill
				(thermal_gap 0.5)
				(thermal_bridge_width 0.5)
				(island_removal_mode 0)
			)
			(polygon
				(pts
					(xy 105.5116 -2.8575) (xy 105.5116 -3.8481) (xy 105.0036 -3.8481) (xy 105.0036 -2.8575)
				)
			)
		)
	)
	(footprint ""
		(layer "F.Cu")
		(at 363.7788 -133.9977)
		(property "Reference" "R7B1"
			(at 0 0 0)
			(layer "F.SilkS")
			(hide yes)
			(effects
				(font
					(size 1.27 1.27)
				)
			)
		)
		(property "Value" ""
			(at 0 0 0)
			(layer "F.Fab")
			(effects
				(font
					(size 1.27 1.27)
				)
			)
		)
		(duplicate_pad_numbers_are_jumpers no)
		(fp_poly
			(pts
				(xy -0.2794 -0.1016) (xy 0.2794 -0.1016) (xy 0.2794 0.9906) (xy -0.2794 0.9906)
			)
			(stroke
				(width 0)
				(type default)
			)
			(fill no)
			(layer "F.CrtYd")
		)
		(fp_line
			(start -0.2794 -0.1016)
			(end -0.2794 0.9906)
			(stroke
				(width 0.1)
				(type default)
			)
			(layer "F.Fab")
		)
		(fp_line
			(start -0.2794 0.9906)
			(end 0.2794 0.9906)
			(stroke
				(width 0.1)
				(type default)
			)
			(layer "F.Fab")
		)
		(fp_line
			(start 0.2794 -0.1016)
			(end -0.2794 -0.1016)
			(stroke
				(width 0.1)
				(type default)
			)
			(layer "F.Fab")
		)
		(fp_line
			(start 0.2794 0.9906)
			(end 0.2794 -0.1016)
			(stroke
				(width 0.1)
				(type default)
			)
			(layer "F.Fab")
		)
		(pad "1" smd rect
			(at 0 0)
			(size 0.508 0.508)
			(layers "F.Cu" "F.Mask" "F.Paste")
			(net "IRQ_PVDDQ_DEF_VRHOT_LVT3_R_N")
		)
		(pad "2" smd rect
			(at 0 0.889)
			(size 0.508 0.508)
			(layers "F.Cu" "F.Mask" "F.Paste")
			(net "IRQ_PVDDQ_DEF_VRHOT_LVT3_N")
		)
		(zone
			(layer "F.Cu")
			(hatch none 0.5)
			(connect_pads
				(clearance 0)
			)
			(min_thickness 0.25)
			(keepout
				(tracks allowed)
				(vias not_allowed)
				(pads allowed)
				(copperpour not_allowed)
				(footprints allowed)
			)
			(placement
				(enabled no)
				(sheetname "")
			)
			(fill
				(thermal_gap 0.5)
				(thermal_bridge_width 0.5)
				(island_removal_mode 0)
			)
			(polygon
				(pts
					(xy 363.5248 -133.7437) (xy 364.0328 -133.7437) (xy 364.0328 -133.3627) (xy 363.5248 -133.3627)
				)
			)
		)
		(zone
			(layer "F.Cu")
			(hatch none 0.5)
			(connect_pads
				(clearance 0)
			)
			(min_thickness 0.25)
			(keepout
				(tracks not_allowed)
				(vias allowed)
				(pads allowed)
				(copperpour not_allowed)
				(footprints allowed)
			)
			(placement
				(enabled no)
				(sheetname "")
			)
			(fill
				(thermal_gap 0.5)
				(thermal_bridge_width 0.5)
				(island_removal_mode 0)
			)
			(polygon
				(pts
					(xy 363.5248 -133.3627) (xy 364.0328 -133.3627) (xy 364.0328 -133.7437) (xy 363.5248 -133.7437)
				)
			)
		)
	)
)
